(kicad_pcb
	(version 20260206)
	(generator "pcbnew")
	(generator_version "10.0")
	(general
		(thickness 1.6)
		(legacy_teardrops no)
	)
	(paper "A4")
	(title_block
		(title "03242023_DA0F0TMBIJ0_F0T_Motherboard_J_brd_V01_OCP.brd")
		(comment 1 "Grand Teton / footprints 3760-3766 of 6105")
	)
	(layers
		(0 "F.Cu" signal "TOP")
		(4 "In1.Cu" signal "GND")
		(6 "In2.Cu" signal "IN1")
		(8 "In3.Cu" signal "GND1")
		(10 "In4.Cu" signal "IN2")
		(12 "In5.Cu" signal "GND2")
		(14 "In6.Cu" signal "IN3")
		(16 "In7.Cu" signal "GND3")
		(18 "In8.Cu" signal "VCC")
		(20 "In9.Cu" signal "VCC1")
		(22 "In10.Cu" signal "GND4")
		(24 "In11.Cu" signal "IN4")
		(26 "In12.Cu" signal "GND5")
		(28 "In13.Cu" signal "IN5")
		(30 "In14.Cu" signal "GND6")
		(32 "In15.Cu" signal "IN6")
		(34 "In16.Cu" signal "GND7")
		(2 "B.Cu" signal "BOTTOM")
		(9 "F.Adhes" user "F.Adhesive")
		(11 "B.Adhes" user "B.Adhesive")
		(13 "F.Paste" user "Package Geometry/Pastemask Top")
		(15 "B.Paste" user "Package Geometry/Pastemask Bottom")
		(5 "F.SilkS" user "Ref Des/Silkscreen Top")
		(7 "B.SilkS" user "Ref Des/Silkscreen Bottom")
		(1 "F.Mask" user "Board Geometry/Soldermask Top")
		(3 "B.Mask" user "Board Geometry/Soldermask Bottom")
		(17 "Dwgs.User" user "User.Drawings")
		(19 "Cmts.User" user "User.Comments")
		(21 "Eco1.User" user "User.Eco1")
		(23 "Eco2.User" user "User.Eco2")
		(25 "Edge.Cuts" user "Board Geometry/Outline")
		(27 "Margin" user)
		(31 "F.CrtYd" user "Package Geometry/Place Bound Top")
		(29 "B.CrtYd" user "Package Geometry/Place Bound Bottom")
		(35 "F.Fab" user "Ref Des/Assembly Top")
		(33 "B.Fab" user "Ref Des/Assembly Bottom")
	)
	(footprint ""
		(layer "F.Cu")
		(at 61.845698 -26.99004 90)
		(property "Reference" "PR3852"
			(at 0 0 90)
			(layer "F.SilkS")
			(hide yes)
			(effects
				(font
					(size 1.27 1.27)
				)
			)
		)
		(property "Value" ""
			(at 0 0 90)
			(layer "F.Fab")
			(effects
				(font
					(size 1.27 1.27)
				)
			)
		)
		(duplicate_pad_numbers_are_jumpers no)
		(fp_line
			(start 0.7874 -0.4064)
			(end 0.7874 0.4064)
			(stroke
				(width 0.1524)
				(type default)
			)
			(layer "F.SilkS")
		)
		(fp_line
			(start -0.7874 -0.4064)
			(end 0.7874 -0.4064)
			(stroke
				(width 0.1524)
				(type default)
			)
			(layer "F.SilkS")
		)
		(fp_line
			(start 0.7874 0.4064)
			(end -0.7874 0.4064)
			(stroke
				(width 0.1524)
				(type default)
			)
			(layer "F.SilkS")
		)
		(fp_line
			(start -0.7874 0.4064)
			(end -0.7874 -0.4064)
			(stroke
				(width 0.1524)
				(type default)
			)
			(layer "F.SilkS")
		)
		(fp_line
			(start -0.12065 -0.305054)
			(end -0.12065 -0.2794)
			(stroke
				(width 0.1)
				(type default)
			)
			(layer "F.Fab")
		)
		(fp_line
			(start -0.67945 -0.305054)
			(end -0.12065 -0.305054)
			(stroke
				(width 0.1)
				(type default)
			)
			(layer "F.Fab")
		)
		(fp_line
			(start 0.67945 -0.3048)
			(end 0.67945 0.3048)
			(stroke
				(width 0.1)
				(type default)
			)
			(layer "F.Fab")
		)
		(fp_line
			(start 0.12065 -0.3048)
			(end 0.67945 -0.3048)
			(stroke
				(width 0.1)
				(type default)
			)
			(layer "F.Fab")
		)
		(fp_line
			(start 0.12065 -0.2794)
			(end 0.12065 -0.3048)
			(stroke
				(width 0.1)
				(type default)
			)
			(layer "F.Fab")
		)
		(fp_line
			(start -0.12065 -0.2794)
			(end 0.12065 -0.2794)
			(stroke
				(width 0.1)
				(type default)
			)
			(layer "F.Fab")
		)
		(fp_line
			(start 0.120396 0.2794)
			(end -0.12065 0.2794)
			(stroke
				(width 0.1)
				(type default)
			)
			(layer "F.Fab")
		)
		(fp_line
			(start -0.12065 0.2794)
			(end -0.12065 0.3048)
			(stroke
				(width 0.1)
				(type default)
			)
			(layer "F.Fab")
		)
		(fp_line
			(start 0.67945 0.3048)
			(end 0.120396 0.3048)
			(stroke
				(width 0.1)
				(type default)
			)
			(layer "F.Fab")
		)
		(fp_line
			(start 0.120396 0.3048)
			(end 0.120396 0.2794)
			(stroke
				(width 0.1)
				(type default)
			)
			(layer "F.Fab")
		)
		(fp_line
			(start -0.12065 0.3048)
			(end -0.67945 0.3048)
			(stroke
				(width 0.1)
				(type default)
			)
			(layer "F.Fab")
		)
		(fp_line
			(start -0.67945 0.3048)
			(end -0.67945 -0.305054)
			(stroke
				(width 0.1)
				(type default)
			)
			(layer "F.Fab")
		)
		(pad "1" smd circle
			(at -0.40005 0 90)
			(size 0 0)
			(layers "F.Cu" "F.Mask" "F.Paste")
			(net "P12V_OCP_V3_2")
		)
		(pad "2" smd circle
			(at 0.40005 0 90)
			(size 0 0)
			(layers "F.Cu" "F.Mask" "F.Paste")
			(net "P12V_OCP_OV_FB_2")
		)
	)
	(footprint ""
		(layer "F.Cu")
		(at 123.769882 -15.54607 180)
		(property "Reference" "R4192"
			(at 0 0 180)
			(layer "F.SilkS")
			(hide yes)
			(effects
				(font
					(size 1.27 1.27)
				)
			)
		)
		(property "Value" ""
			(at 0 0 180)
			(layer "F.Fab")
			(effects
				(font
					(size 1.27 1.27)
				)
			)
		)
		(duplicate_pad_numbers_are_jumpers no)
		(fp_line
			(start 0.7874 0.4064)
			(end -0.7874 0.4064)
			(stroke
				(width 0.1524)
				(type default)
			)
			(layer "F.SilkS")
		)
		(fp_line
			(start 0.7874 -0.4064)
			(end 0.7874 0.4064)
			(stroke
				(width 0.1524)
				(type default)
			)
			(layer "F.SilkS")
		)
		(fp_line
			(start -0.7874 0.4064)
			(end -0.7874 -0.4064)
			(stroke
				(width 0.1524)
				(type default)
			)
			(layer "F.SilkS")
		)
		(fp_line
			(start -0.7874 -0.4064)
			(end 0.7874 -0.4064)
			(stroke
				(width 0.1524)
				(type default)
			)
			(layer "F.SilkS")
		)
		(fp_line
			(start 0.67945 0.3048)
			(end 0.120396 0.3048)
			(stroke
				(width 0.1)
				(type default)
			)
			(layer "F.Fab")
		)
		(fp_line
			(start 0.67945 -0.3048)
			(end 0.67945 0.3048)
			(stroke
				(width 0.1)
				(type default)
			)
			(layer "F.Fab")
		)
		(fp_line
			(start 0.12065 -0.2794)
			(end 0.12065 -0.3048)
			(stroke
				(width 0.1)
				(type default)
			)
			(layer "F.Fab")
		)
		(fp_line
			(start 0.12065 -0.3048)
			(end 0.67945 -0.3048)
			(stroke
				(width 0.1)
				(type default)
			)
			(layer "F.Fab")
		)
		(fp_line
			(start 0.120396 0.3048)
			(end 0.120396 0.2794)
			(stroke
				(width 0.1)
				(type default)
			)
			(layer "F.Fab")
		)
		(fp_line
			(start 0.120396 0.2794)
			(end -0.12065 0.2794)
			(stroke
				(width 0.1)
				(type default)
			)
			(layer "F.Fab")
		)
		(fp_line
			(start -0.12065 0.3048)
			(end -0.67945 0.3048)
			(stroke
				(width 0.1)
				(type default)
			)
			(layer "F.Fab")
		)
		(fp_line
			(start -0.12065 0.2794)
			(end -0.12065 0.3048)
			(stroke
				(width 0.1)
				(type default)
			)
			(layer "F.Fab")
		)
		(fp_line
			(start -0.12065 -0.2794)
			(end 0.12065 -0.2794)
			(stroke
				(width 0.1)
				(type default)
			)
			(layer "F.Fab")
		)
		(fp_line
			(start -0.12065 -0.305054)
			(end -0.12065 -0.2794)
			(stroke
				(width 0.1)
				(type default)
			)
			(layer "F.Fab")
		)
		(fp_line
			(start -0.67945 0.3048)
			(end -0.67945 -0.305054)
			(stroke
				(width 0.1)
				(type default)
			)
			(layer "F.Fab")
		)
		(fp_line
			(start -0.67945 -0.305054)
			(end -0.12065 -0.305054)
			(stroke
				(width 0.1)
				(type default)
			)
			(layer "F.Fab")
		)
		(pad "1" smd circle
			(at -0.40005 0 180)
			(size 0 0)
			(layers "F.Cu" "F.Mask" "F.Paste")
			(net "P3V3_AUX")
		)
		(pad "2" smd circle
			(at 0.40005 0 180)
			(size 0 0)
			(layers "F.Cu" "F.Mask" "F.Paste")
			(net "U273_3_ADD1")
		)
	)
	(footprint ""
		(layer "F.Cu")
		(at 252.961648 -56.193182)
		(property "Reference" "PR3952"
			(at 0 0 0)
			(layer "F.SilkS")
			(hide yes)
			(effects
				(font
					(size 1.27 1.27)
				)
			)
		)
		(property "Value" ""
			(at 0 0 0)
			(layer "F.Fab")
			(effects
				(font
					(size 1.27 1.27)
				)
			)
		)
		(duplicate_pad_numbers_are_jumpers no)
		(fp_line
			(start -0.7874 -0.4064)
			(end 0.7874 -0.4064)
			(stroke
				(width 0.1524)
				(type default)
			)
			(layer "F.SilkS")
		)
		(fp_line
			(start -0.7874 0.4064)
			(end -0.7874 -0.4064)
			(stroke
				(width 0.1524)
				(type default)
			)
			(layer "F.SilkS")
		)
		(fp_line
			(start 0.7874 -0.4064)
			(end 0.7874 0.4064)
			(stroke
				(width 0.1524)
				(type default)
			)
			(layer "F.SilkS")
		)
		(fp_line
			(start 0.7874 0.4064)
			(end -0.7874 0.4064)
			(stroke
				(width 0.1524)
				(type default)
			)
			(layer "F.SilkS")
		)
		(fp_line
			(start -0.67945 -0.305054)
			(end -0.12065 -0.305054)
			(stroke
				(width 0.1)
				(type default)
			)
			(layer "F.Fab")
		)
		(fp_line
			(start -0.67945 0.3048)
			(end -0.67945 -0.305054)
			(stroke
				(width 0.1)
				(type default)
			)
			(layer "F.Fab")
		)
		(fp_line
			(start -0.12065 -0.305054)
			(end -0.12065 -0.2794)
			(stroke
				(width 0.1)
				(type default)
			)
			(layer "F.Fab")
		)
		(fp_line
			(start -0.12065 -0.2794)
			(end 0.12065 -0.2794)
			(stroke
				(width 0.1)
				(type default)
			)
			(layer "F.Fab")
		)
		(fp_line
			(start -0.12065 0.2794)
			(end -0.12065 0.3048)
			(stroke
				(width 0.1)
				(type default)
			)
			(layer "F.Fab")
		)
		(fp_line
			(start -0.12065 0.3048)
			(end -0.67945 0.3048)
			(stroke
				(width 0.1)
				(type default)
			)
			(layer "F.Fab")
		)
		(fp_line
			(start 0.120396 0.2794)
			(end -0.12065 0.2794)
			(stroke
				(width 0.1)
				(type default)
			)
			(layer "F.Fab")
		)
		(fp_line
			(start 0.120396 0.3048)
			(end 0.120396 0.2794)
			(stroke
				(width 0.1)
				(type default)
			)
			(layer "F.Fab")
		)
		(fp_line
			(start 0.12065 -0.3048)
			(end 0.67945 -0.3048)
			(stroke
				(width 0.1)
				(type default)
			)
			(layer "F.Fab")
		)
		(fp_line
			(start 0.12065 -0.2794)
			(end 0.12065 -0.3048)
			(stroke
				(width 0.1)
				(type default)
			)
			(layer "F.Fab")
		)
		(fp_line
			(start 0.67945 -0.3048)
			(end 0.67945 0.3048)
			(stroke
				(width 0.1)
				(type default)
			)
			(layer "F.Fab")
		)
		(fp_line
			(start 0.67945 0.3048)
			(end 0.120396 0.3048)
			(stroke
				(width 0.1)
				(type default)
			)
			(layer "F.Fab")
		)
		(pad "1" smd circle
			(at -0.40005 0)
			(size 0 0)
			(layers "F.Cu" "F.Mask" "F.Paste")
			(net "P12V_E1S_0")
		)
		(pad "2" smd circle
			(at 0.40005 0)
			(size 0 0)
			(layers "F.Cu" "F.Mask" "F.Paste")
			(net "P12V_E1S_OV_FB_0")
		)
	)
	(footprint ""
		(layer "F.Cu")
		(at 320.190622 -60.620148)
		(property "Reference" "R1477"
			(at 0 0 0)
			(layer "F.SilkS")
			(hide yes)
			(effects
				(font
					(size 1.27 1.27)
				)
			)
		)
		(property "Value" ""
			(at 0 0 0)
			(layer "F.Fab")
			(effects
				(font
					(size 1.27 1.27)
				)
			)
		)
		(duplicate_pad_numbers_are_jumpers no)
		(fp_line
			(start -0.7874 -0.4064)
			(end 0.7874 -0.4064)
			(stroke
				(width 0.1524)
				(type default)
			)
			(layer "F.SilkS")
		)
		(fp_line
			(start -0.7874 0.4064)
			(end -0.7874 -0.4064)
			(stroke
				(width 0.1524)
				(type default)
			)
			(layer "F.SilkS")
		)
		(fp_line
			(start 0.7874 -0.4064)
			(end 0.7874 0.4064)
			(stroke
				(width 0.1524)
				(type default)
			)
			(layer "F.SilkS")
		)
		(fp_line
			(start 0.7874 0.4064)
			(end -0.7874 0.4064)
			(stroke
				(width 0.1524)
				(type default)
			)
			(layer "F.SilkS")
		)
		(fp_line
			(start -0.67945 -0.305054)
			(end -0.12065 -0.305054)
			(stroke
				(width 0.1)
				(type default)
			)
			(layer "F.Fab")
		)
		(fp_line
			(start -0.67945 0.3048)
			(end -0.67945 -0.305054)
			(stroke
				(width 0.1)
				(type default)
			)
			(layer "F.Fab")
		)
		(fp_line
			(start -0.12065 -0.305054)
			(end -0.12065 -0.2794)
			(stroke
				(width 0.1)
				(type default)
			)
			(layer "F.Fab")
		)
		(fp_line
			(start -0.12065 -0.2794)
			(end 0.12065 -0.2794)
			(stroke
				(width 0.1)
				(type default)
			)
			(layer "F.Fab")
		)
		(fp_line
			(start -0.12065 0.2794)
			(end -0.12065 0.3048)
			(stroke
				(width 0.1)
				(type default)
			)
			(layer "F.Fab")
		)
		(fp_line
			(start -0.12065 0.3048)
			(end -0.67945 0.3048)
			(stroke
				(width 0.1)
				(type default)
			)
			(layer "F.Fab")
		)
		(fp_line
			(start 0.120396 0.2794)
			(end -0.12065 0.2794)
			(stroke
				(width 0.1)
				(type default)
			)
			(layer "F.Fab")
		)
		(fp_line
			(start 0.120396 0.3048)
			(end 0.120396 0.2794)
			(stroke
				(width 0.1)
				(type default)
			)
			(layer "F.Fab")
		)
		(fp_line
			(start 0.12065 -0.3048)
			(end 0.67945 -0.3048)
			(stroke
				(width 0.1)
				(type default)
			)
			(layer "F.Fab")
		)
		(fp_line
			(start 0.12065 -0.2794)
			(end 0.12065 -0.3048)
			(stroke
				(width 0.1)
				(type default)
			)
			(layer "F.Fab")
		)
		(fp_line
			(start 0.67945 -0.3048)
			(end 0.67945 0.3048)
			(stroke
				(width 0.1)
				(type default)
			)
			(layer "F.Fab")
		)
		(fp_line
			(start 0.67945 0.3048)
			(end 0.120396 0.3048)
			(stroke
				(width 0.1)
				(type default)
			)
			(layer "F.Fab")
		)
		(pad "1" smd circle
			(at -0.40005 0)
			(size 0 0)
			(layers "F.Cu" "F.Mask" "F.Paste")
			(net "P3V3_AUX")
		)
		(pad "2" smd circle
			(at 0.40005 0)
			(size 0 0)
			(layers "F.Cu" "F.Mask" "F.Paste")
			(net "FM_PCH_XTAL_INPUT_MODE_MGPIO_TE")
		)
	)
	(footprint ""
		(layer "F.Cu")
		(at 371.29847 -435.600094)
		(property "Reference" "H93"
			(at -6.50113 -4.379976 0)
			(unlocked yes)
			(layer "F.SilkS")
			(effects
				(font
					(size 0.7874 0.5842)
					(thickness 0.1524)
				)
				(justify left)
			)
		)
		(property "Value" ""
			(at 0 0 0)
			(layer "F.Fab")
			(effects
				(font
					(size 1.27 1.27)
				)
			)
		)
		(duplicate_pad_numbers_are_jumpers no)
		(pad "1" thru_hole circle
			(at 0 0)
			(size 10.0076 10.0076)
			(drill 5.6134)
			(layers "*.Cu" "*.Mask")
			(remove_unused_layers no)
			(net "GND")
			(clearance -1.9431)
		)
	)
	(footprint ""
		(layer "F.Cu")
		(at 144.635474 -402.371052 -90)
		(property "Reference" "C759"
			(at 0 0 270)
			(layer "F.SilkS")
			(hide yes)
			(effects
				(font
					(size 1.27 1.27)
				)
			)
		)
		(property "Value" ""
			(at 0 0 270)
			(layer "F.Fab")
			(effects
				(font
					(size 1.27 1.27)
				)
			)
		)
		(duplicate_pad_numbers_are_jumpers no)
		(fp_line
			(start -0.299974 0.150114)
			(end -0.299974 -0.150114)
			(stroke
				(width 0.1)
				(type default)
			)
			(layer "F.Fab")
		)
		(fp_line
			(start 0.299974 0.150114)
			(end -0.299974 0.150114)
			(stroke
				(width 0.1)
				(type default)
			)
			(layer "F.Fab")
		)
		(fp_line
			(start -0.299974 -0.150114)
			(end 0.299974 -0.150114)
			(stroke
				(width 0.1)
				(type default)
			)
			(layer "F.Fab")
		)
		(fp_line
			(start 0.299974 -0.150114)
			(end 0.299974 0.150114)
			(stroke
				(width 0.1)
				(type default)
			)
			(layer "F.Fab")
		)
		(pad "1" smd rect
			(at -0.2667 0 270)
			(size 0.3048 0.381)
			(layers "F.Cu" "F.Mask" "F.Paste")
			(net "P5E_CPU1_PE2_TX_C_DP<7>")
		)
		(pad "2" smd rect
			(at 0.2667 0 270)
			(size 0.3048 0.381)
			(layers "F.Cu" "F.Mask" "F.Paste")
			(net "P5E_CPU1_PE2_TX_DP<7>")
		)
	)
	(footprint ""
		(layer "F.Cu")
		(at 39.827454 -107.031282 180)
		(property "Reference" "R3682"
			(at 0 0 180)
			(layer "F.SilkS")
			(hide yes)
			(effects
				(font
					(size 1.27 1.27)
				)
			)
		)
		(property "Value" ""
			(at 0 0 180)
			(layer "F.Fab")
			(effects
				(font
					(size 1.27 1.27)
				)
			)
		)
		(duplicate_pad_numbers_are_jumpers no)
		(fp_line
			(start 0.7874 0.4064)
			(end -0.7874 0.4064)
			(stroke
				(width 0.1524)
				(type default)
			)
			(layer "F.SilkS")
		)
		(fp_line
			(start 0.7874 -0.4064)
			(end 0.7874 0.4064)
			(stroke
				(width 0.1524)
				(type default)
			)
			(layer "F.SilkS")
		)
		(fp_line
			(start -0.7874 0.4064)
			(end -0.7874 -0.4064)
			(stroke
				(width 0.1524)
				(type default)
			)
			(layer "F.SilkS")
		)
		(fp_line
			(start -0.7874 -0.4064)
			(end 0.7874 -0.4064)
			(stroke
				(width 0.1524)
				(type default)
			)
			(layer "F.SilkS")
		)
		(fp_line
			(start 0.67945 0.3048)
			(end 0.120396 0.3048)
			(stroke
				(width 0.1)
				(type default)
			)
			(layer "F.Fab")
		)
		(fp_line
			(start 0.67945 -0.3048)
			(end 0.67945 0.3048)
			(stroke
				(width 0.1)
				(type default)
			)
			(layer "F.Fab")
		)
		(fp_line
			(start 0.12065 -0.2794)
			(end 0.12065 -0.3048)
			(stroke
				(width 0.1)
				(type default)
			)
			(layer "F.Fab")
		)
		(fp_line
			(start 0.12065 -0.3048)
			(end 0.67945 -0.3048)
			(stroke
				(width 0.1)
				(type default)
			)
			(layer "F.Fab")
		)
		(fp_line
			(start 0.120396 0.3048)
			(end 0.120396 0.2794)
			(stroke
				(width 0.1)
				(type default)
			)
			(layer "F.Fab")
		)
		(fp_line
			(start 0.120396 0.2794)
			(end -0.12065 0.2794)
			(stroke
				(width 0.1)
				(type default)
			)
			(layer "F.Fab")
		)
		(fp_line
			(start -0.12065 0.3048)
			(end -0.67945 0.3048)
			(stroke
				(width 0.1)
				(type default)
			)
			(layer "F.Fab")
		)
		(fp_line
			(start -0.12065 0.2794)
			(end -0.12065 0.3048)
			(stroke
				(width 0.1)
				(type default)
			)
			(layer "F.Fab")
		)
		(fp_line
			(start -0.12065 -0.2794)
			(end 0.12065 -0.2794)
			(stroke
				(width 0.1)
				(type default)
			)
			(layer "F.Fab")
		)
		(fp_line
			(start -0.12065 -0.305054)
			(end -0.12065 -0.2794)
			(stroke
				(width 0.1)
				(type default)
			)
			(layer "F.Fab")
		)
		(fp_line
			(start -0.67945 0.3048)
			(end -0.67945 -0.305054)
			(stroke
				(width 0.1)
				(type default)
			)
			(layer "F.Fab")
		)
		(fp_line
			(start -0.67945 -0.305054)
			(end -0.12065 -0.305054)
			(stroke
				(width 0.1)
				(type default)
			)
			(layer "F.Fab")
		)
		(pad "1" smd rect
			(at -0.40005 0)
			(size 0.4572 0.508)
			(layers "F.Cu" "F.Mask" "F.Paste")
			(net "P3V3_AUX_ADC")
		)
		(pad "2" smd rect
			(at 0.40005 0)
			(size 0.4572 0.508)
			(layers "F.Cu" "F.Mask" "F.Paste")
			(net "P3V3_AUX_ADC_TIC")
		)
	)
)
